# BASEBOARD_FAB2 (Tioga Pass) — schematic netlist excerpt (pin names and nets, part order shuffled) for the footprints in the layout excerpt that follows; sources: Cadence DE-HDL packaged netlist, KiCad conversion of Wiwynn_Tioga_Pass_MB.brd

R7D33  374R2F-1-GP  1%  pkg SMD-RG  page 92 : \1\ = P3V3 ; \2\ = P0V7_GTL2104_VREF_0
R1F2  RES  100.0 1% CHIP  pkg 0402  page 161 : A = FAN_TACH0 ; B = FAN_TACH0_CPU0_D2
C9E9  CAP  15.0PF 50V 5% COG  pkg 0402LF  page 139 : A = XTAL_25MHZ_IN ; B = GND

(kicad_pcb
	(version 20260206)
	(generator "pcbnew")
	(generator_version "10.0")
	(general
		(thickness 1.6)
		(legacy_teardrops no)
	)
	(paper "A4")
	(title_block
		(title "Wiwynn_Tioga_Pass_MB.brd")
		(comment 1 "Tioga Pass / footprints 1148-1150 of 4770")
	)
	(layers
		(0 "F.Cu" signal "TOP")
		(4 "In1.Cu" signal "L2GND")
		(6 "In2.Cu" signal "L3")
		(8 "In3.Cu" signal "L4GND")
		(10 "In4.Cu" signal "L5")
		(12 "In5.Cu" signal "L6GND")
		(14 "In6.Cu" signal "L7VCC")
		(16 "In7.Cu" signal "L8VCC")
		(18 "In8.Cu" signal "L9GND")
		(20 "In9.Cu" signal "L10")
		(22 "In10.Cu" signal "L11GND")
		(24 "In11.Cu" signal "L12")
		(26 "In12.Cu" signal "L13GND")
		(2 "B.Cu" signal "BOTTOM")
		(9 "F.Adhes" user "F.Adhesive")
		(11 "B.Adhes" user "B.Adhesive")
		(13 "F.Paste" user "Package Geometry/Pastemask Top")
		(15 "B.Paste" user "Package Geometry/Pastemask Bottom")
		(5 "F.SilkS" user "Ref Des/Silkscreen Top")
		(7 "B.SilkS" user "Ref Des/Silkscreen Bottom")
		(1 "F.Mask" user "Board Geometry/Soldermask Top")
		(3 "B.Mask" user "Board Geometry/Soldermask Bottom")
		(17 "Dwgs.User" user "User.Drawings")
		(19 "Cmts.User" user "User.Comments")
		(21 "Eco1.User" user "User.Eco1")
		(23 "Eco2.User" user "User.Eco2")
		(25 "Edge.Cuts" user "Board Geometry/Outline")
		(27 "Margin" user)
		(31 "F.CrtYd" user "Package Geometry/Place Bound Top")
		(29 "B.CrtYd" user "Package Geometry/Place Bound Bottom")
		(35 "F.Fab" user "Ref Des/Assembly Top")
		(33 "B.Fab" user "Ref Des/Assembly Bottom")
	)
	(footprint ""
		(layer "F.Cu")
		(at 26.543 -29.972 -90)
		(property "Reference" "R1F2"
			(at 0 0 270)
			(layer "F.SilkS")
			(hide yes)
			(effects
				(font
					(size 1.27 1.27)
				)
			)
		)
		(property "Value" ""
			(at 0 0 270)
			(layer "F.Fab")
			(effects
				(font
					(size 1.27 1.27)
				)
			)
		)
		(duplicate_pad_numbers_are_jumpers no)
		(fp_rect
			(start -0.2794 -0.1016)
			(end 0.2794 0.9906)
			(stroke
				(width 0)
				(type default)
			)
			(fill no)
			(layer "F.CrtYd")
		)
		(fp_line
			(start -0.2794 0.9906)
			(end 0.2794 0.9906)
			(stroke
				(width 0.1)
				(type default)
			)
			(layer "F.Fab")
		)
		(fp_line
			(start 0.2794 0.9906)
			(end 0.2794 -0.1016)
			(stroke
				(width 0.1)
				(type default)
			)
			(layer "F.Fab")
		)
		(fp_line
			(start -0.2794 -0.1016)
			(end -0.2794 0.9906)
			(stroke
				(width 0.1)
				(type default)
			)
			(layer "F.Fab")
		)
		(fp_line
			(start 0.2794 -0.1016)
			(end -0.2794 -0.1016)
			(stroke
				(width 0.1)
				(type default)
			)
			(layer "F.Fab")
		)
		(pad "1" smd rect
			(at 0 0 270)
			(size 0.508 0.508)
			(layers "F.Cu" "F.Mask" "F.Paste")
			(net "FAN_TACH0")
		)
		(pad "2" smd rect
			(at 0 0.889 270)
			(size 0.508 0.508)
			(layers "F.Cu" "F.Mask" "F.Paste")
			(net "FAN_TACH0_CPU0_D2")
		)
		(zone
			(layer "F.Cu")
			(hatch none 0.5)
			(connect_pads
				(clearance 0)
			)
			(min_thickness 0.25)
			(keepout
				(tracks not_allowed)
				(vias allowed)
				(pads allowed)
				(copperpour not_allowed)
				(footprints allowed)
			)
			(placement
				(enabled no)
				(sheetname "")
			)
			(fill
				(thermal_gap 0.5)
				(thermal_bridge_width 0.5)
				(island_removal_mode 0)
			)
			(polygon
				(pts
					(xy 26.289 -30.226) (xy 25.908 -30.226) (xy 25.908 -29.718) (xy 26.289 -29.718)
				)
			)
		)
		(zone
			(layer "F.Cu")
			(hatch none 0.5)
			(connect_pads
				(clearance 0)
			)
			(min_thickness 0.25)
			(keepout
				(tracks allowed)
				(vias not_allowed)
				(pads allowed)
				(copperpour not_allowed)
				(footprints allowed)
			)
			(placement
				(enabled no)
				(sheetname "")
			)
			(fill
				(thermal_gap 0.5)
				(thermal_bridge_width 0.5)
				(island_removal_mode 0)
			)
			(polygon
				(pts
					(xy 26.289 -30.226) (xy 25.908 -30.226) (xy 25.908 -29.718) (xy 26.289 -29.718)
				)
			)
		)
	)
	(footprint ""
		(layer "F.Cu")
		(at 476.4786 -41.2369)
		(property "Reference" "C9E9"
			(at 0 0 0)
			(layer "F.SilkS")
			(hide yes)
			(effects
				(font
					(size 1.27 1.27)
				)
			)
		)
		(property "Value" ""
			(at 0 0 0)
			(layer "F.Fab")
			(effects
				(font
					(size 1.27 1.27)
				)
			)
		)
		(duplicate_pad_numbers_are_jumpers no)
		(fp_poly
			(pts
				(xy 0.3048 -0.1016) (xy 0.3048 0.9906) (xy -0.3048 0.9906) (xy -0.3048 -0.1016)
			)
			(stroke
				(width 0)
				(type default)
			)
			(fill no)
			(layer "F.CrtYd")
		)
		(fp_line
			(start -0.3048 -0.1016)
			(end -0.3048 0.9906)
			(stroke
				(width 0.1)
				(type default)
			)
			(layer "F.Fab")
		)
		(fp_line
			(start -0.3048 0.9906)
			(end 0.3048 0.9906)
			(stroke
				(width 0.1)
				(type default)
			)
			(layer "F.Fab")
		)
		(fp_line
			(start 0.3048 -0.1016)
			(end -0.3048 -0.1016)
			(stroke
				(width 0.1)
				(type default)
			)
			(layer "F.Fab")
		)
		(fp_line
			(start 0.3048 0.9906)
			(end 0.3048 -0.1016)
			(stroke
				(width 0.1)
				(type default)
			)
			(layer "F.Fab")
		)
		(pad "1" smd rect
			(at 0 0)
			(size 0.508 0.508)
			(layers "F.Cu" "F.Mask" "F.Paste")
			(net "XTAL_25MHZ_IN")
		)
		(pad "2" smd rect
			(at 0 0.889)
			(size 0.508 0.508)
			(layers "F.Cu" "F.Mask" "F.Paste")
			(net "GND")
		)
		(zone
			(layer "F.Cu")
			(hatch none 0.5)
			(connect_pads
				(clearance 0)
			)
			(min_thickness 0.25)
			(keepout
				(tracks allowed)
				(vias not_allowed)
				(pads allowed)
				(copperpour not_allowed)
				(footprints allowed)
			)
			(placement
				(enabled no)
				(sheetname "")
			)
			(fill
				(thermal_gap 0.5)
				(thermal_bridge_width 0.5)
				(island_removal_mode 0)
			)
			(polygon
				(pts
					(xy 476.2246 -40.9829) (xy 476.7326 -40.9829) (xy 476.7326 -40.6019) (xy 476.2246 -40.6019)
				)
			)
		)
		(zone
			(layer "F.Cu")
			(hatch none 0.5)
			(connect_pads
				(clearance 0)
			)
			(min_thickness 0.25)
			(keepout
				(tracks not_allowed)
				(vias allowed)
				(pads allowed)
				(copperpour not_allowed)
				(footprints allowed)
			)
			(placement
				(enabled no)
				(sheetname "")
			)
			(fill
				(thermal_gap 0.5)
				(thermal_bridge_width 0.5)
				(island_removal_mode 0)
			)
			(polygon
				(pts
					(xy 476.2246 -40.6019) (xy 476.7326 -40.6019) (xy 476.7326 -40.9829) (xy 476.2246 -40.9829)
				)
			)
		)
	)
	(footprint ""
		(layer "F.Cu")
		(at 391.4902 -80.0354 180)
		(property "Reference" "R7D33"
			(at 0 0 180)
			(layer "F.SilkS")
			(hide yes)
			(effects
				(font
					(size 1.27 1.27)
				)
			)
		)
		(property "Value" "*"
			(at 0.064008 -4.108196 180)
			(unlocked yes)
			(layer "F.Fab")
			(hide yes)
			(effects
				(font
					(size 1.27 1.016)
					(thickness 0.1524)
				)
			)
		)
		(property "Device Type" "374R2F-1-GP_SMD-RG-374R2F-1-GPA"
			(at 0.064008 -5.632196 180)
			(unlocked yes)
			(layer "F.Fab")
			(hide yes)
			(effects
				(font
					(size 1.27 1.016)
					(thickness 0.1524)
				)
			)
		)
		(duplicate_pad_numbers_are_jumpers no)
		(fp_line
			(start 0.508 -0.9398)
			(end -0.508 -0.9398)
			(stroke
				(width 0.1524)
				(type default)
			)
			(layer "F.SilkS")
		)
		(fp_line
			(start -0.508 -0.9398)
			(end -0.508 0.9398)
			(stroke
				(width 0.1524)
				(type default)
			)
			(layer "F.SilkS")
		)
		(fp_rect
			(start -0.508 0.9398)
			(end 0.508 -0.9398)
			(stroke
				(width 0)
				(type default)
			)
			(fill no)
			(layer "F.CrtYd")
		)
		(fp_rect
			(start -0.508 0.9398)
			(end 0.508 -0.9398)
			(stroke
				(width 0)
				(type default)
			)
			(fill no)
			(layer "F.Fab")
		)
		(pad "1" smd custom
			(at 0 -0.4445 180)
			(size 0.1397 0.1397)
			(layers "F.Cu" "F.Mask" "F.Paste")
			(net "P3V3")
			(options
				(clearance outline)
				(anchor circle)
			)
			(primitives
				(gr_poly
					(pts
						(arc
							(start -0.1778 -0.2794)
							(mid -0.249642 -0.249642)
							(end -0.2794 -0.1778)
						)
						(arc
							(start -0.2794 0.1778)
							(mid -0.249642 0.249642)
							(end -0.1778 0.2794)
						)
						(arc
							(start 0.1778 0.2794)
							(mid 0.249642 0.249642)
							(end 0.2794 0.1778)
						)
						(arc
							(start 0.2794 -0.1778)
							(mid 0.249642 -0.249642)
							(end 0.1778 -0.2794)
						)
					)
					(width 0)
					(fill yes)
				)
			)
		)
		(pad "2" smd custom
			(at 0 0.4445 180)
			(size 0.1397 0.1397)
			(layers "F.Cu" "F.Mask" "F.Paste")
			(net "P0V7_GTL2104_VREF_0")
			(options
				(clearance outline)
				(anchor circle)
			)
			(primitives
				(gr_poly
					(pts
						(arc
							(start -0.1778 -0.2794)
							(mid -0.249642 -0.249642)
							(end -0.2794 -0.1778)
						)
						(arc
							(start -0.2794 0.1778)
							(mid -0.249642 0.249642)
							(end -0.1778 0.2794)
						)
						(arc
							(start 0.1778 0.2794)
							(mid 0.249642 0.249642)
							(end 0.2794 0.1778)
						)
						(arc
							(start 0.2794 -0.1778)
							(mid 0.249642 -0.249642)
							(end 0.1778 -0.2794)
						)
					)
					(width 0)
					(fill yes)
				)
			)
		)
	)
)
